(kicad_pcb
	(version 20260206)
	(generator "pcbnew")
	(generator_version "10.0")
	(general
		(thickness 1.6)
		(legacy_teardrops no)
	)
	(paper "A4")
	(title_block
		(title "Bryce Canyon_IOM_M2_16342-2_OCP.brd")
		(comment 1 "Bryce Canyon / footprints 163-169 of 1146")
	)
	(layers
		(0 "F.Cu" signal "TOP")
		(4 "In1.Cu" signal "L2GND")
		(6 "In2.Cu" signal "L3")
		(8 "In3.Cu" signal "L4VCC")
		(10 "In4.Cu" signal "L5VCC")
		(12 "In5.Cu" signal "L6")
		(14 "In6.Cu" signal "L7GND")
		(2 "B.Cu" signal "BOTTOM")
		(9 "F.Adhes" user "F.Adhesive")
		(11 "B.Adhes" user "B.Adhesive")
		(13 "F.Paste" user "Package Geometry/Pastemask Top")
		(15 "B.Paste" user "Package Geometry/Pastemask Bottom")
		(5 "F.SilkS" user "Ref Des/Silkscreen Top")
		(7 "B.SilkS" user "Ref Des/Silkscreen Bottom")
		(1 "F.Mask" user "Board Geometry/Soldermask Top")
		(3 "B.Mask" user "Board Geometry/Soldermask Bottom")
		(17 "Dwgs.User" user "User.Drawings")
		(19 "Cmts.User" user "User.Comments")
		(21 "Eco1.User" user "User.Eco1")
		(23 "Eco2.User" user "User.Eco2")
		(25 "Edge.Cuts" user "Board Geometry/Outline")
		(27 "Margin" user)
		(31 "F.CrtYd" user "Package Geometry/Place Bound Top")
		(29 "B.CrtYd" user "Package Geometry/Place Bound Bottom")
		(35 "F.Fab" user "Ref Des/Assembly Top")
		(33 "B.Fab" user "Ref Des/Assembly Bottom")
	)
	(footprint ""
		(layer "F.Cu")
		(at 25.682702 -132.353558 180)
		(property "Reference" "R232"
			(at 0 0 180)
			(layer "F.SilkS")
			(hide yes)
			(effects
				(font
					(size 1.27 1.27)
				)
			)
		)
		(property "Value" "120R2F-GP"
			(at 0.064008 -3.993896 180)
			(unlocked yes)
			(layer "F.Fab")
			(hide yes)
			(effects
				(font
					(size 1.016 1.016)
					(thickness 0.1524)
				)
			)
		)
		(property "Device Type" "R402H16"
			(at 0.064008 -5.517896 180)
			(unlocked yes)
			(layer "F.Fab")
			(hide yes)
			(effects
				(font
					(size 1.016 1.016)
					(thickness 0.1524)
				)
			)
		)
		(duplicate_pad_numbers_are_jumpers no)
		(fp_line
			(start 0.508 -0.9398)
			(end -0.508 -0.9398)
			(stroke
				(width 0.1524)
				(type default)
			)
			(layer "F.SilkS")
		)
		(fp_line
			(start -0.508 -0.9398)
			(end -0.508 0.9398)
			(stroke
				(width 0.1524)
				(type default)
			)
			(layer "F.SilkS")
		)
		(fp_rect
			(start -0.508 0.9398)
			(end 0.508 -0.9398)
			(stroke
				(width 0)
				(type default)
			)
			(fill no)
			(layer "F.CrtYd")
		)
		(fp_rect
			(start -0.508 0.9398)
			(end 0.508 -0.9398)
			(stroke
				(width 0)
				(type default)
			)
			(fill no)
			(layer "F.Fab")
		)
		(pad "1" smd custom
			(at 0 -0.4445 180)
			(size 0.1397 0.1397)
			(layers "F.Cu" "F.Mask" "F.Paste")
			(net "MEMBA_1")
			(options
				(clearance outline)
				(anchor circle)
			)
			(primitives
				(gr_poly
					(pts
						(arc
							(start -0.1778 -0.2794)
							(mid -0.249642 -0.249642)
							(end -0.2794 -0.1778)
						)
						(arc
							(start -0.2794 0.1778)
							(mid -0.249642 0.249642)
							(end -0.1778 0.2794)
						)
						(arc
							(start 0.1778 0.2794)
							(mid 0.249642 0.249642)
							(end 0.2794 0.1778)
						)
						(arc
							(start 0.2794 -0.1778)
							(mid 0.249642 -0.249642)
							(end 0.1778 -0.2794)
						)
					)
					(width 0)
					(fill yes)
				)
			)
		)
		(pad "2" smd custom
			(at 0 0.4445 180)
			(size 0.1397 0.1397)
			(layers "F.Cu" "F.Mask" "F.Paste")
			(net "P1V2_STBY")
			(options
				(clearance outline)
				(anchor circle)
			)
			(primitives
				(gr_poly
					(pts
						(arc
							(start -0.1778 -0.2794)
							(mid -0.249642 -0.249642)
							(end -0.2794 -0.1778)
						)
						(arc
							(start -0.2794 0.1778)
							(mid -0.249642 0.249642)
							(end -0.1778 0.2794)
						)
						(arc
							(start 0.1778 0.2794)
							(mid 0.249642 0.249642)
							(end 0.2794 0.1778)
						)
						(arc
							(start 0.2794 -0.1778)
							(mid 0.249642 -0.249642)
							(end 0.1778 -0.2794)
						)
					)
					(width 0)
					(fill yes)
				)
			)
		)
	)
	(footprint ""
		(layer "F.Cu")
		(at 81.407 -152.146 -90)
		(property "Reference" "C44"
			(at 0 0 270)
			(layer "F.SilkS")
			(hide yes)
			(effects
				(font
					(size 1.27 1.27)
				)
			)
		)
		(property "Value" "SCD1U16V2KX-3GP"
			(at 1.1811 -2.7051 270)
			(unlocked yes)
			(layer "F.Fab")
			(hide yes)
			(effects
				(font
					(size 1.016 1.016)
					(thickness 0.1524)
				)
			)
		)
		(property "Device Type" "C402H22"
			(at 1.1811 -4.2291 270)
			(unlocked yes)
			(layer "F.Fab")
			(hide yes)
			(effects
				(font
					(size 1.016 1.016)
					(thickness 0.1524)
				)
			)
		)
		(duplicate_pad_numbers_are_jumpers no)
		(fp_rect
			(start -0.4318 0.9525)
			(end 0.4318 -0.9525)
			(stroke
				(width 0)
				(type default)
			)
			(fill no)
			(layer "F.CrtYd")
		)
		(fp_rect
			(start -0.4318 0.9525)
			(end 0.4318 -0.9525)
			(stroke
				(width 0)
				(type default)
			)
			(fill no)
			(layer "F.Fab")
		)
		(pad "1" smd custom
			(at 0 -0.4445 270)
			(size 0.1524 0.1524)
			(layers "F.Cu" "F.Mask" "F.Paste")
			(net "P3V3_STBY")
			(options
				(clearance outline)
				(anchor circle)
			)
			(primitives
				(gr_poly
					(pts
						(arc
							(start 0.3048 -0.2032)
							(mid 0.275042 -0.275042)
							(end 0.2032 -0.3048)
						)
						(arc
							(start -0.2032 -0.3048)
							(mid -0.275042 -0.275042)
							(end -0.3048 -0.2032)
						)
						(arc
							(start -0.3048 0.2032)
							(mid -0.275042 0.275042)
							(end -0.2032 0.3048)
						)
						(arc
							(start 0.2032 0.3048)
							(mid 0.275042 0.275042)
							(end 0.3048 0.2032)
						)
					)
					(width 0)
					(fill yes)
				)
			)
		)
		(pad "2" smd custom
			(at 0 0.4445 270)
			(size 0.1524 0.1524)
			(layers "F.Cu" "F.Mask" "F.Paste")
			(net "GND")
			(options
				(clearance outline)
				(anchor circle)
			)
			(primitives
				(gr_poly
					(pts
						(arc
							(start 0.3048 -0.2032)
							(mid 0.275042 -0.275042)
							(end 0.2032 -0.3048)
						)
						(arc
							(start -0.2032 -0.3048)
							(mid -0.275042 -0.275042)
							(end -0.3048 -0.2032)
						)
						(arc
							(start -0.3048 0.2032)
							(mid -0.275042 0.275042)
							(end -0.2032 0.3048)
						)
						(arc
							(start 0.2032 0.3048)
							(mid 0.275042 0.275042)
							(end 0.3048 0.2032)
						)
					)
					(width 0)
					(fill yes)
				)
			)
		)
	)
	(footprint ""
		(layer "F.Cu")
		(at 99.2886 -162.0266 -90)
		(property "Reference" "R32"
			(at 0 0 270)
			(layer "F.SilkS")
			(hide yes)
			(effects
				(font
					(size 1.27 1.27)
				)
			)
		)
		(property "Value" "4K7R2F-GP"
			(at 0.064008 -3.993896 270)
			(unlocked yes)
			(layer "F.Fab")
			(hide yes)
			(effects
				(font
					(size 1.016 1.016)
					(thickness 0.1524)
				)
			)
		)
		(property "Device Type" "R402H16"
			(at 0.064008 -5.517896 270)
			(unlocked yes)
			(layer "F.Fab")
			(hide yes)
			(effects
				(font
					(size 1.016 1.016)
					(thickness 0.1524)
				)
			)
		)
		(duplicate_pad_numbers_are_jumpers no)
		(fp_line
			(start -0.508 -0.9398)
			(end -0.508 0.9398)
			(stroke
				(width 0.1524)
				(type default)
			)
			(layer "F.SilkS")
		)
		(fp_line
			(start 0.508 -0.9398)
			(end -0.508 -0.9398)
			(stroke
				(width 0.1524)
				(type default)
			)
			(layer "F.SilkS")
		)
		(fp_rect
			(start -0.508 0.9398)
			(end 0.508 -0.9398)
			(stroke
				(width 0)
				(type default)
			)
			(fill no)
			(layer "F.CrtYd")
		)
		(fp_rect
			(start -0.508 0.9398)
			(end 0.508 -0.9398)
			(stroke
				(width 0)
				(type default)
			)
			(fill no)
			(layer "F.Fab")
		)
		(pad "1" smd custom
			(at 0 -0.4445 270)
			(size 0.1397 0.1397)
			(layers "F.Cu" "F.Mask" "F.Paste")
			(net "P3V3_STBY")
			(options
				(clearance outline)
				(anchor circle)
			)
			(primitives
				(gr_poly
					(pts
						(arc
							(start -0.1778 -0.2794)
							(mid -0.249642 -0.249642)
							(end -0.2794 -0.1778)
						)
						(arc
							(start -0.2794 0.1778)
							(mid -0.249642 0.249642)
							(end -0.1778 0.2794)
						)
						(arc
							(start 0.1778 0.2794)
							(mid 0.249642 0.249642)
							(end 0.2794 0.1778)
						)
						(arc
							(start 0.2794 -0.1778)
							(mid 0.249642 -0.249642)
							(end 0.1778 -0.2794)
						)
					)
					(width 0)
					(fill yes)
				)
			)
		)
		(pad "2" smd custom
			(at 0 0.4445 270)
			(size 0.1397 0.1397)
			(layers "F.Cu" "F.Mask" "F.Paste")
			(net "USB_SUSP_IND")
			(options
				(clearance outline)
				(anchor circle)
			)
			(primitives
				(gr_poly
					(pts
						(arc
							(start -0.1778 -0.2794)
							(mid -0.249642 -0.249642)
							(end -0.2794 -0.1778)
						)
						(arc
							(start -0.2794 0.1778)
							(mid -0.249642 0.249642)
							(end -0.1778 0.2794)
						)
						(arc
							(start 0.1778 0.2794)
							(mid 0.249642 0.249642)
							(end 0.2794 0.1778)
						)
						(arc
							(start 0.2794 -0.1778)
							(mid 0.249642 -0.249642)
							(end 0.1778 -0.2794)
						)
					)
					(width 0)
					(fill yes)
				)
			)
		)
	)
	(footprint ""
		(layer "F.Cu")
		(at 124.841 -6.604 -90)
		(property "Reference" "R711"
			(at 0 0 270)
			(layer "F.SilkS")
			(hide yes)
			(effects
				(font
					(size 1.27 1.27)
				)
			)
		)
		(property "Value" "0R2J-2-GP"
			(at 0.064008 -3.993896 270)
			(unlocked yes)
			(layer "F.Fab")
			(hide yes)
			(effects
				(font
					(size 1.016 1.016)
					(thickness 0.1524)
				)
			)
		)
		(property "Device Type" "R402H16"
			(at 0.064008 -5.517896 270)
			(unlocked yes)
			(layer "F.Fab")
			(hide yes)
			(effects
				(font
					(size 1.016 1.016)
					(thickness 0.1524)
				)
			)
		)
		(duplicate_pad_numbers_are_jumpers no)
		(fp_line
			(start -0.508 -0.9398)
			(end -0.508 0.9398)
			(stroke
				(width 0.1524)
				(type default)
			)
			(layer "F.SilkS")
		)
		(fp_line
			(start 0.508 -0.9398)
			(end -0.508 -0.9398)
			(stroke
				(width 0.1524)
				(type default)
			)
			(layer "F.SilkS")
		)
		(fp_rect
			(start -0.508 0.9398)
			(end 0.508 -0.9398)
			(stroke
				(width 0)
				(type default)
			)
			(fill no)
			(layer "F.CrtYd")
		)
		(fp_rect
			(start -0.508 0.9398)
			(end 0.508 -0.9398)
			(stroke
				(width 0)
				(type default)
			)
			(fill no)
			(layer "F.Fab")
		)
		(pad "1" smd custom
			(at 0 -0.4445 270)
			(size 0.1397 0.1397)
			(layers "F.Cu" "F.Mask" "F.Paste")
			(net "I2C_IOM_SCL")
			(options
				(clearance outline)
				(anchor circle)
			)
			(primitives
				(gr_poly
					(pts
						(arc
							(start -0.1778 -0.2794)
							(mid -0.249642 -0.249642)
							(end -0.2794 -0.1778)
						)
						(arc
							(start -0.2794 0.1778)
							(mid -0.249642 0.249642)
							(end -0.1778 0.2794)
						)
						(arc
							(start 0.1778 0.2794)
							(mid 0.249642 0.249642)
							(end 0.2794 0.1778)
						)
						(arc
							(start 0.2794 -0.1778)
							(mid 0.249642 -0.249642)
							(end 0.1778 -0.2794)
						)
					)
					(width 0)
					(fill yes)
				)
			)
		)
		(pad "2" smd custom
			(at 0 0.4445 270)
			(size 0.1397 0.1397)
			(layers "F.Cu" "F.Mask" "F.Paste")
			(net "HSW_SCL")
			(options
				(clearance outline)
				(anchor circle)
			)
			(primitives
				(gr_poly
					(pts
						(arc
							(start -0.1778 -0.2794)
							(mid -0.249642 -0.249642)
							(end -0.2794 -0.1778)
						)
						(arc
							(start -0.2794 0.1778)
							(mid -0.249642 0.249642)
							(end -0.1778 0.2794)
						)
						(arc
							(start 0.1778 0.2794)
							(mid 0.249642 0.249642)
							(end 0.2794 0.1778)
						)
						(arc
							(start 0.2794 -0.1778)
							(mid 0.249642 -0.249642)
							(end 0.1778 -0.2794)
						)
					)
					(width 0)
					(fill yes)
				)
			)
		)
	)
	(footprint ""
		(layer "F.Cu")
		(at 182.446676 -105.37825)
		(property "Reference" "U84"
			(at 0 0 0)
			(layer "F.SilkS")
			(hide yes)
			(effects
				(font
					(size 1.27 1.27)
				)
			)
		)
		(property "Value" "TMP75AIDGKR-GP"
			(at -0.1143 -9.1948 0)
			(unlocked yes)
			(layer "F.Fab")
			(hide yes)
			(effects
				(font
					(size 1.016 1.016)
					(thickness 0.1524)
				)
			)
		)
		(property "Device Type" "MSOP8-1H44"
			(at -0.1143 -10.795 0)
			(unlocked yes)
			(layer "F.Fab")
			(hide yes)
			(effects
				(font
					(size 1.016 1.016)
					(thickness 0.1524)
				)
			)
		)
		(duplicate_pad_numbers_are_jumpers no)
		(fp_line
			(start -1.9558 -1.016)
			(end -1.9558 1.016)
			(stroke
				(width 0.1524)
				(type default)
			)
			(layer "F.SilkS")
		)
		(fp_line
			(start -1.9558 -0.5461)
			(end -1.4478 -0.0381)
			(stroke
				(width 0.1524)
				(type default)
			)
			(layer "F.SilkS")
		)
		(fp_line
			(start -1.9558 1.016)
			(end 1.0795 1.016)
			(stroke
				(width 0.1524)
				(type default)
			)
			(layer "F.SilkS")
		)
		(fp_line
			(start -1.778 1.0922)
			(end -1.778 3.048)
			(stroke
				(width 0.508)
				(type default)
			)
			(layer "F.SilkS")
		)
		(fp_line
			(start -1.4478 -0.0381)
			(end -1.9558 0.4699)
			(stroke
				(width 0.1524)
				(type default)
			)
			(layer "F.SilkS")
		)
		(fp_line
			(start 1.0795 -1.016)
			(end -1.9558 -1.016)
			(stroke
				(width 0.1524)
				(type default)
			)
			(layer "F.SilkS")
		)
		(fp_line
			(start 1.0795 1.016)
			(end 1.0795 -1.016)
			(stroke
				(width 0.1524)
				(type default)
			)
			(layer "F.SilkS")
		)
		(fp_poly
			(pts
				(xy -1.1557 -1.016) (xy -1.1557 1.016) (xy 1.1557 1.016) (xy 1.1557 -1.016)
			)
			(stroke
				(width 0)
				(type default)
			)
			(fill yes)
			(layer "F.SilkS")
		)
		(fp_rect
			(start -1.4986 2.4511)
			(end 1.4986 -2.4511)
			(stroke
				(width 0)
				(type default)
			)
			(fill no)
			(layer "F.CrtYd")
		)
		(fp_poly
			(pts
				(xy -2.032 3.302) (xy -2.032 -3.302) (xy 2.032 -3.302) (xy 2.032 -2.1209) (xy 1.4986 -2.1209) (xy 1.4986 -2.4511)
				(xy -1.4986 -2.4511) (xy -1.4986 2.4511) (xy 1.4986 2.4511) (xy 1.4986 -2.1082) (xy 2.032 -2.1082)
				(xy 2.032 3.302)
			)
			(stroke
				(width 0)
				(type default)
			)
			(fill no)
			(layer "F.CrtYd")
		)
		(fp_rect
			(start -2.032 3.302)
			(end 2.032 -3.302)
			(stroke
				(width 0)
				(type default)
			)
			(fill no)
			(layer "F.Fab")
		)
		(pad "1" smd rect
			(at -0.97536 2.05486)
			(size 0.3556 1.524)
			(layers "F.Cu" "F.Mask" "F.Paste")
			(net "TEMP_1_SDA")
		)
		(pad "2" smd rect
			(at -0.32512 2.05486)
			(size 0.3556 1.524)
			(layers "F.Cu" "F.Mask" "F.Paste")
			(net "TEMP_1_SCL")
		)
		(pad "3" smd rect
			(at 0.32512 2.05486)
			(size 0.3556 1.524)
			(layers "F.Cu" "F.Mask" "F.Paste")
			(net "TEMP_1_ALERT")
		)
		(pad "4" smd rect
			(at 0.97536 2.05486)
			(size 0.3556 1.524)
			(layers "F.Cu" "F.Mask" "F.Paste")
			(net "GND")
		)
		(pad "5" smd rect
			(at 0.97536 -2.05486)
			(size 0.3556 1.524)
			(layers "F.Cu" "F.Mask" "F.Paste")
			(net "TEMP_1_A2")
		)
		(pad "6" smd rect
			(at 0.32512 -2.05486)
			(size 0.3556 1.524)
			(layers "F.Cu" "F.Mask" "F.Paste")
			(net "TEMP_1_A1")
		)
		(pad "7" smd rect
			(at -0.32512 -2.05486)
			(size 0.3556 1.524)
			(layers "F.Cu" "F.Mask" "F.Paste")
			(net "TEMP_1_A0")
		)
		(pad "8" smd rect
			(at -0.97536 -2.05486)
			(size 0.3556 1.524)
			(layers "F.Cu" "F.Mask" "F.Paste")
			(net "P3V3_STBY")
		)
	)
	(footprint ""
		(layer "F.Cu")
		(at 47.879 -175.7172)
		(property "Reference" "C49"
			(at 0 0 0)
			(layer "F.SilkS")
			(hide yes)
			(effects
				(font
					(size 1.27 1.27)
				)
			)
		)
		(property "Value" "SCD1U16V2KX-3GP"
			(at 1.1811 -2.7051 0)
			(unlocked yes)
			(layer "F.Fab")
			(hide yes)
			(effects
				(font
					(size 1.016 1.016)
					(thickness 0.1524)
				)
			)
		)
		(property "Device Type" "C402H22"
			(at 1.1811 -4.2291 0)
			(unlocked yes)
			(layer "F.Fab")
			(hide yes)
			(effects
				(font
					(size 1.016 1.016)
					(thickness 0.1524)
				)
			)
		)
		(duplicate_pad_numbers_are_jumpers no)
		(fp_rect
			(start -0.4318 0.9525)
			(end 0.4318 -0.9525)
			(stroke
				(width 0)
				(type default)
			)
			(fill no)
			(layer "F.CrtYd")
		)
		(fp_rect
			(start -0.4318 0.9525)
			(end 0.4318 -0.9525)
			(stroke
				(width 0)
				(type default)
			)
			(fill no)
			(layer "F.Fab")
		)
		(pad "1" smd custom
			(at 0 -0.4445)
			(size 0.1524 0.1524)
			(layers "F.Cu" "F.Mask" "F.Paste")
			(net "P3V3_STBY")
			(options
				(clearance outline)
				(anchor circle)
			)
			(primitives
				(gr_poly
					(pts
						(arc
							(start 0.3048 -0.2032)
							(mid 0.275042 -0.275042)
							(end 0.2032 -0.3048)
						)
						(arc
							(start -0.2032 -0.3048)
							(mid -0.275042 -0.275042)
							(end -0.3048 -0.2032)
						)
						(arc
							(start -0.3048 0.2032)
							(mid -0.275042 0.275042)
							(end -0.2032 0.3048)
						)
						(arc
							(start 0.2032 0.3048)
							(mid 0.275042 0.275042)
							(end 0.3048 0.2032)
						)
					)
					(width 0)
					(fill yes)
				)
			)
		)
		(pad "2" smd custom
			(at 0 0.4445)
			(size 0.1524 0.1524)
			(layers "F.Cu" "F.Mask" "F.Paste")
			(net "GND")
			(options
				(clearance outline)
				(anchor circle)
			)
			(primitives
				(gr_poly
					(pts
						(arc
							(start 0.3048 -0.2032)
							(mid 0.275042 -0.275042)
							(end 0.2032 -0.3048)
						)
						(arc
							(start -0.2032 -0.3048)
							(mid -0.275042 -0.275042)
							(end -0.3048 -0.2032)
						)
						(arc
							(start -0.3048 0.2032)
							(mid -0.275042 0.275042)
							(end -0.2032 0.3048)
						)
						(arc
							(start 0.2032 0.3048)
							(mid 0.275042 0.275042)
							(end 0.3048 0.2032)
						)
					)
					(width 0)
					(fill yes)
				)
			)
		)
	)
	(footprint ""
		(layer "F.Cu")
		(at 86.872572 -58.973974 90)
		(property "Reference" "R4"
			(at 0 0 90)
			(layer "F.SilkS")
			(hide yes)
			(effects
				(font
					(size 1.27 1.27)
				)
			)
		)
		(property "Value" "0R2J-2-GP"
			(at 0.064008 -3.993896 90)
			(unlocked yes)
			(layer "F.Fab")
			(hide yes)
			(effects
				(font
					(size 1.016 1.016)
					(thickness 0.1524)
				)
			)
		)
		(property "Device Type" "R402H16"
			(at 0.064008 -5.517896 90)
			(unlocked yes)
			(layer "F.Fab")
			(hide yes)
			(effects
				(font
					(size 1.016 1.016)
					(thickness 0.1524)
				)
			)
		)
		(duplicate_pad_numbers_are_jumpers no)
		(fp_line
			(start 0.508 -0.9398)
			(end -0.508 -0.9398)
			(stroke
				(width 0.1524)
				(type default)
			)
			(layer "F.SilkS")
		)
		(fp_line
			(start -0.508 -0.9398)
			(end -0.508 0.9398)
			(stroke
				(width 0.1524)
				(type default)
			)
			(layer "F.SilkS")
		)
		(fp_rect
			(start -0.508 0.9398)
			(end 0.508 -0.9398)
			(stroke
				(width 0)
				(type default)
			)
			(fill no)
			(layer "F.CrtYd")
		)
		(fp_rect
			(start -0.508 0.9398)
			(end 0.508 -0.9398)
			(stroke
				(width 0)
				(type default)
			)
			(fill no)
			(layer "F.Fab")
		)
		(pad "1" smd custom
			(at 0 -0.4445 90)
			(size 0.1397 0.1397)
			(layers "F.Cu" "F.Mask" "F.Paste")
			(net "I2C_MEZZ_ALERT_R_N")
			(options
				(clearance outline)
				(anchor circle)
			)
			(primitives
				(gr_poly
					(pts
						(arc
							(start -0.1778 -0.2794)
							(mid -0.249642 -0.249642)
							(end -0.2794 -0.1778)
						)
						(arc
							(start -0.2794 0.1778)
							(mid -0.249642 0.249642)
							(end -0.1778 0.2794)
						)
						(arc
							(start 0.1778 0.2794)
							(mid 0.249642 0.249642)
							(end 0.2794 0.1778)
						)
						(arc
							(start 0.2794 -0.1778)
							(mid 0.249642 -0.249642)
							(end 0.1778 -0.2794)
						)
					)
					(width 0)
					(fill yes)
				)
			)
		)
		(pad "2" smd custom
			(at 0 0.4445 90)
			(size 0.1397 0.1397)
			(layers "F.Cu" "F.Mask" "F.Paste")
			(net "I2C_MEZZ_ALERT_N")
			(options
				(clearance outline)
				(anchor circle)
			)
			(primitives
				(gr_poly
					(pts
						(arc
							(start -0.1778 -0.2794)
							(mid -0.249642 -0.249642)
							(end -0.2794 -0.1778)
						)
						(arc
							(start -0.2794 0.1778)
							(mid -0.249642 0.249642)
							(end -0.1778 0.2794)
						)
						(arc
							(start 0.1778 0.2794)
							(mid 0.249642 0.249642)
							(end 0.2794 0.1778)
						)
						(arc
							(start 0.2794 -0.1778)
							(mid 0.249642 -0.249642)
							(end 0.1778 -0.2794)
						)
					)
					(width 0)
					(fill yes)
				)
			)
		)
	)
)
